# T6G (Grand Teton) — schematic netlist excerpt (pin names and nets, part order shuffled) for the footprints in the layout excerpt that follows; sources: Cadence DE-HDL packaged netlist, KiCad conversion of 04192023_DAF0TMB3IC0_F0TG_MB_C_brd_V02_OCP.brd

PC623_4  Q_CAP  0.1UF 25V 10% X7R  pkg 0402  page 223 : A = SW_P12V_AUX_PVDDIO_P1_FLT ; B = GND
C2606  Q_CAP  22UF 4V 20% X6S  pkg C0402  page 70 : A = PVDDIO_P0 ; B = GND

(kicad_pcb
	(version 20260206)
	(generator "pcbnew")
	(generator_version "10.0")
	(general
		(thickness 1.6)
		(legacy_teardrops no)
	)
	(paper "A4")
	(title_block
		(title "04192023_DAF0TMB3IC0_F0TG_MB_C_brd_V02_OCP.brd")
		(comment 1 "Grand Teton / footprints 1473-1474 of 8354")
	)
	(layers
		(0 "F.Cu" signal "TOP")
		(4 "In1.Cu" signal "GND")
		(6 "In2.Cu" signal "IN1")
		(8 "In3.Cu" signal "GND1")
		(10 "In4.Cu" signal "IN2")
		(12 "In5.Cu" signal "GND2")
		(14 "In6.Cu" signal "IN3")
		(16 "In7.Cu" signal "GND3")
		(18 "In8.Cu" signal "VCC")
		(20 "In9.Cu" signal "VCC1")
		(22 "In10.Cu" signal "GND4")
		(24 "In11.Cu" signal "IN4")
		(26 "In12.Cu" signal "GND5")
		(28 "In13.Cu" signal "IN5")
		(30 "In14.Cu" signal "GND6")
		(32 "In15.Cu" signal "IN6")
		(34 "In16.Cu" signal "GND7")
		(2 "B.Cu" signal "BOTTOM")
		(9 "F.Adhes" user "F.Adhesive")
		(11 "B.Adhes" user "B.Adhesive")
		(13 "F.Paste" user "Package Geometry/Pastemask Top")
		(15 "B.Paste" user "Package Geometry/Pastemask Bottom")
		(5 "F.SilkS" user "Ref Des/Silkscreen Top")
		(7 "B.SilkS" user "Ref Des/Silkscreen Bottom")
		(1 "F.Mask" user "Board Geometry/Soldermask Top")
		(3 "B.Mask" user "Board Geometry/Soldermask Bottom")
		(17 "Dwgs.User" user "User.Drawings")
		(19 "Cmts.User" user "User.Comments")
		(21 "Eco1.User" user "User.Eco1")
		(23 "Eco2.User" user "User.Eco2")
		(25 "Edge.Cuts" user "Board Geometry/Outline")
		(27 "Margin" user)
		(31 "F.CrtYd" user "Package Geometry/Place Bound Top")
		(29 "B.CrtYd" user "Package Geometry/Place Bound Bottom")
		(35 "F.Fab" user "Ref Des/Assembly Top")
		(33 "B.Fab" user "Ref Des/Assembly Bottom")
	)
	(footprint ""
		(layer "F.Cu")
		(at 353.900232 -257.455162)
		(property "Reference" "C2606"
			(at 0 0 0)
			(layer "F.SilkS")
			(hide yes)
			(effects
				(font
					(size 1.27 1.27)
				)
			)
		)
		(property "Value" ""
			(at 0 0 0)
			(layer "F.Fab")
			(effects
				(font
					(size 1.27 1.27)
				)
			)
		)
		(duplicate_pad_numbers_are_jumpers no)
		(fp_line
			(start -0.7874 -0.4064)
			(end 0.7874 -0.4064)
			(stroke
				(width 0.1524)
				(type default)
			)
			(layer "F.SilkS")
		)
		(fp_line
			(start -0.7874 0.4064)
			(end -0.7874 -0.4064)
			(stroke
				(width 0.1524)
				(type default)
			)
			(layer "F.SilkS")
		)
		(fp_line
			(start 0.7874 -0.4064)
			(end 0.7874 0.4064)
			(stroke
				(width 0.1524)
				(type default)
			)
			(layer "F.SilkS")
		)
		(fp_line
			(start 0.7874 0.4064)
			(end -0.7874 0.4064)
			(stroke
				(width 0.1524)
				(type default)
			)
			(layer "F.SilkS")
		)
		(fp_line
			(start -0.67945 -0.305054)
			(end -0.12065 -0.305054)
			(stroke
				(width 0.1)
				(type default)
			)
			(layer "F.Fab")
		)
		(fp_line
			(start -0.67945 0.3048)
			(end -0.67945 -0.305054)
			(stroke
				(width 0.1)
				(type default)
			)
			(layer "F.Fab")
		)
		(fp_line
			(start -0.12065 -0.305054)
			(end -0.12065 -0.2794)
			(stroke
				(width 0.1)
				(type default)
			)
			(layer "F.Fab")
		)
		(fp_line
			(start -0.12065 -0.2794)
			(end 0.12065 -0.2794)
			(stroke
				(width 0.1)
				(type default)
			)
			(layer "F.Fab")
		)
		(fp_line
			(start -0.12065 0.2794)
			(end -0.12065 0.3048)
			(stroke
				(width 0.1)
				(type default)
			)
			(layer "F.Fab")
		)
		(fp_line
			(start -0.12065 0.3048)
			(end -0.67945 0.3048)
			(stroke
				(width 0.1)
				(type default)
			)
			(layer "F.Fab")
		)
		(fp_line
			(start 0.120396 0.2794)
			(end -0.12065 0.2794)
			(stroke
				(width 0.1)
				(type default)
			)
			(layer "F.Fab")
		)
		(fp_line
			(start 0.120396 0.3048)
			(end 0.120396 0.2794)
			(stroke
				(width 0.1)
				(type default)
			)
			(layer "F.Fab")
		)
		(fp_line
			(start 0.12065 -0.3048)
			(end 0.67945 -0.3048)
			(stroke
				(width 0.1)
				(type default)
			)
			(layer "F.Fab")
		)
		(fp_line
			(start 0.12065 -0.2794)
			(end 0.12065 -0.3048)
			(stroke
				(width 0.1)
				(type default)
			)
			(layer "F.Fab")
		)
		(fp_line
			(start 0.67945 -0.3048)
			(end 0.67945 0.3048)
			(stroke
				(width 0.1)
				(type default)
			)
			(layer "F.Fab")
		)
		(fp_line
			(start 0.67945 0.3048)
			(end 0.120396 0.3048)
			(stroke
				(width 0.1)
				(type default)
			)
			(layer "F.Fab")
		)
		(pad "1" smd circle
			(at -0.40005 0)
			(size 0 0)
			(layers "F.Cu" "F.Mask" "F.Paste")
			(net "PVDDIO_P0")
		)
		(pad "2" smd circle
			(at 0.40005 0)
			(size 0 0)
			(layers "F.Cu" "F.Mask" "F.Paste")
			(net "GND")
		)
	)
	(footprint ""
		(layer "F.Cu")
		(at 57.738518 -351.10547)
		(property "Reference" "PC623_4"
			(at 0 0 0)
			(layer "F.SilkS")
			(hide yes)
			(effects
				(font
					(size 1.27 1.27)
				)
			)
		)
		(property "Value" ""
			(at 0 0 0)
			(layer "F.Fab")
			(effects
				(font
					(size 1.27 1.27)
				)
			)
		)
		(duplicate_pad_numbers_are_jumpers no)
		(fp_line
			(start -0.7874 -0.4064)
			(end 0.7874 -0.4064)
			(stroke
				(width 0.1524)
				(type default)
			)
			(layer "F.SilkS")
		)
		(fp_line
			(start -0.7874 0.4064)
			(end -0.7874 -0.4064)
			(stroke
				(width 0.1524)
				(type default)
			)
			(layer "F.SilkS")
		)
		(fp_line
			(start 0.7874 -0.4064)
			(end 0.7874 0.4064)
			(stroke
				(width 0.1524)
				(type default)
			)
			(layer "F.SilkS")
		)
		(fp_line
			(start 0.7874 0.4064)
			(end -0.7874 0.4064)
			(stroke
				(width 0.1524)
				(type default)
			)
			(layer "F.SilkS")
		)
		(fp_line
			(start -0.67945 -0.305054)
			(end -0.12065 -0.305054)
			(stroke
				(width 0.1)
				(type default)
			)
			(layer "F.Fab")
		)
		(fp_line
			(start -0.67945 0.3048)
			(end -0.67945 -0.305054)
			(stroke
				(width 0.1)
				(type default)
			)
			(layer "F.Fab")
		)
		(fp_line
			(start -0.12065 -0.305054)
			(end -0.12065 -0.2794)
			(stroke
				(width 0.1)
				(type default)
			)
			(layer "F.Fab")
		)
		(fp_line
			(start -0.12065 -0.2794)
			(end 0.12065 -0.2794)
			(stroke
				(width 0.1)
				(type default)
			)
			(layer "F.Fab")
		)
		(fp_line
			(start -0.12065 0.2794)
			(end -0.12065 0.3048)
			(stroke
				(width 0.1)
				(type default)
			)
			(layer "F.Fab")
		)
		(fp_line
			(start -0.12065 0.3048)
			(end -0.67945 0.3048)
			(stroke
				(width 0.1)
				(type default)
			)
			(layer "F.Fab")
		)
		(fp_line
			(start 0.120396 0.2794)
			(end -0.12065 0.2794)
			(stroke
				(width 0.1)
				(type default)
			)
			(layer "F.Fab")
		)
		(fp_line
			(start 0.120396 0.3048)
			(end 0.120396 0.2794)
			(stroke
				(width 0.1)
				(type default)
			)
			(layer "F.Fab")
		)
		(fp_line
			(start 0.12065 -0.3048)
			(end 0.67945 -0.3048)
			(stroke
				(width 0.1)
				(type default)
			)
			(layer "F.Fab")
		)
		(fp_line
			(start 0.12065 -0.2794)
			(end 0.12065 -0.3048)
			(stroke
				(width 0.1)
				(type default)
			)
			(layer "F.Fab")
		)
		(fp_line
			(start 0.67945 -0.3048)
			(end 0.67945 0.3048)
			(stroke
				(width 0.1)
				(type default)
			)
			(layer "F.Fab")
		)
		(fp_line
			(start 0.67945 0.3048)
			(end 0.120396 0.3048)
			(stroke
				(width 0.1)
				(type default)
			)
			(layer "F.Fab")
		)
		(pad "1" smd circle
			(at -0.40005 0)
			(size 0 0)
			(layers "F.Cu" "F.Mask" "F.Paste")
			(net "SW_P12V_AUX_PVDDIO_P1_FLT")
		)
		(pad "2" smd circle
			(at 0.40005 0)
			(size 0 0)
			(layers "F.Cu" "F.Mask" "F.Paste")
			(net "GND")
		)
	)
)
